(kicad_pcb
	(version 20240108)
	(generator "pcbnew")
	(generator_version "8.0")
	(general
		(thickness 1.6)
		(legacy_teardrops no)
	)
	(paper "A4")
	(title_block
		(title "Jetson Orin Baseboard OCuLink Expansion")
		(date "2025-03-18")
		(rev "1.1.0")
		(company "Antmicro Ltd")
		(comment 1 "www.antmicro.com")
		(comment 9 "footprints 19-22 of 119")
	)
	(layers
		(0 "F.Cu" signal)
		(1 "In1.Cu" signal)
		(2 "In2.Cu" signal)
		(31 "B.Cu" signal)
		(32 "B.Adhes" user "B.Adhesive")
		(33 "F.Adhes" user "F.Adhesive")
		(34 "B.Paste" user)
		(35 "F.Paste" user)
		(36 "B.SilkS" user "B.Silkscreen")
		(37 "F.SilkS" user "F.Silkscreen")
		(38 "B.Mask" user)
		(39 "F.Mask" user)
		(40 "Dwgs.User" user "User.Drawings")
		(41 "Cmts.User" user "User.Comments")
		(42 "Eco1.User" user "User.Eco1")
		(43 "Eco2.User" user "User.Eco2")
		(44 "Edge.Cuts" user)
		(45 "Margin" user)
		(46 "B.CrtYd" user "B.Courtyard")
		(47 "F.CrtYd" user "F.Courtyard")
		(48 "B.Fab" user)
		(49 "F.Fab" user)
	)
	(footprint "antmicro-footprints:R_0402_1005Metric"
		(layer "F.Cu")
		(at 146.22 144.66)
		(descr "Resistor SMD 0402")
		(tags "resistor SMD 0402")
		(property "Reference" "R33"
			(at -1.09 1.49 0)
			(layer "F.SilkS")
			(effects
				(font
					(size 0.7 0.7)
					(thickness 0.15)
				)
				(justify left bottom)
			)
		)
		(property "Value" "R_1k_0402"
			(at -1.011843 1.772047 0)
			(layer "F.Fab")
			(effects
				(font
					(size 0.7 0.7)
					(thickness 0.15)
				)
				(justify left bottom)
			)
		)
		(property "Footprint" "antmicro-footprints:R_0402_1005Metric"
			(at 0 0 0)
			(layer "F.Fab")
			(hide yes)
			(effects
				(font
					(size 1.27 1.27)
					(thickness 0.15)
				)
			)
		)
		(property "Datasheet" "https://www.bourns.com/docs/product-datasheets/cr.pdf"
			(at 0 0 0)
			(layer "F.Fab")
			(hide yes)
			(effects
				(font
					(size 1.27 1.27)
					(thickness 0.15)
				)
			)
		)
		(property "Description" "SMD Chip Resistor, 1 kohm, ± 1%, 63 mW, 0402 [1005 Metric], Thick Film, General Purpose"
			(at 0 0 0)
			(layer "F.Fab")
			(hide yes)
			(effects
				(font
					(size 1.27 1.27)
					(thickness 0.15)
				)
			)
		)
		(property "MPN" "CR0402-FX-1001GLF"
			(at 0 0 0)
			(unlocked yes)
			(layer "F.Fab")
			(hide yes)
			(effects
				(font
					(size 1 1)
					(thickness 0.15)
				)
			)
		)
		(property "Manufacturer" "Bourns"
			(at 0 0 0)
			(unlocked yes)
			(layer "F.Fab")
			(hide yes)
			(effects
				(font
					(size 1 1)
					(thickness 0.15)
				)
			)
		)
		(property "License" "Apache-2.0"
			(at 0 0 0)
			(unlocked yes)
			(layer "F.Fab")
			(hide yes)
			(effects
				(font
					(size 1 1)
					(thickness 0.15)
				)
			)
		)
		(property "Author" "Antmicro"
			(at 0 0 0)
			(unlocked yes)
			(layer "F.Fab")
			(hide yes)
			(effects
				(font
					(size 1 1)
					(thickness 0.15)
				)
			)
		)
		(property "Val" "1k"
			(at 0 0 0)
			(unlocked yes)
			(layer "F.Fab")
			(hide yes)
			(effects
				(font
					(size 1 1)
					(thickness 0.15)
				)
			)
		)
		(property "Tolerance" "1%"
			(at 0 0 0)
			(unlocked yes)
			(layer "F.Fab")
			(hide yes)
			(effects
				(font
					(size 1 1)
					(thickness 0.15)
				)
			)
		)
		(property "Public" "False"
			(at 0 0 0)
			(unlocked yes)
			(layer "F.Fab")
			(hide yes)
			(effects
				(font
					(size 1 1)
					(thickness 0.15)
				)
			)
		)
		(sheetname "Root")
		(sheetfile "jetson-orin-baseboard-oculink-expansion.kicad_sch")
		(attr smd)
		(fp_rect
			(start -0.925 -0.47)
			(end 0.925 0.47)
			(stroke
				(width 0.05)
				(type default)
			)
			(fill none)
			(layer "F.CrtYd")
		)
		(fp_rect
			(start -0.5 -0.25)
			(end 0.5 0.25)
			(stroke
				(width 0.15)
				(type solid)
			)
			(fill none)
			(layer "F.Fab")
		)
		(fp_text user "License: Apache-2.0"
			(at -0.95 5.169 0)
			(layer "F.Fab")
			(hide yes)
			(effects
				(font
					(size 0.7 0.7)
					(thickness 0.15)
				)
				(justify left bottom)
			)
		)
		(fp_text user "Author: Antmicro"
			(at -0.95 4.169 0)
			(layer "F.Fab")
			(hide yes)
			(effects
				(font
					(size 0.7 0.7)
					(thickness 0.15)
				)
				(justify left bottom)
			)
		)
		(fp_text user "${REFERENCE}"
			(at -0.95 3.168 0)
			(layer "F.Fab")
			(hide yes)
			(effects
				(font
					(size 0.7 0.7)
					(thickness 0.15)
				)
				(justify left bottom)
			)
		)
		(pad "1" smd roundrect
			(at -0.48 0)
			(size 0.59 0.64)
			(layers "F.Cu" "F.Paste" "F.Mask")
			(roundrect_rratio 0.25)
			(net 71 "/~{CPRSNT}")
			(pintype "passive")
		)
		(pad "2" smd roundrect
			(at 0.48 0)
			(size 0.59 0.64)
			(layers "F.Cu" "F.Paste" "F.Mask")
			(roundrect_rratio 0.25)
			(net 51 "GND")
			(pintype "passive")
		)
	)
	(footprint "antmicro-footprints:TP_SMD_0.75mm"
		(layer "F.Cu")
		(at 130.005 112.903751 180)
		(property "Reference" "TP11"
			(at -2.385 1.303751 0)
			(layer "F.SilkS")
			(effects
				(font
					(size 0.7 0.7)
					(thickness 0.15)
				)
				(justify right top)
			)
		)
		(property "Value" "TP_0.75mm_SMD"
			(at 0 1.2 0)
			(layer "F.Fab")
			(effects
				(font
					(size 0.7 0.7)
					(thickness 0.15)
				)
				(justify right top)
			)
		)
		(property "Footprint" "antmicro-footprints:TP_SMD_0.75mm"
			(at 0 0 0)
			(layer "F.Fab")
			(hide yes)
			(effects
				(font
					(size 1.27 1.27)
					(thickness 0.15)
				)
			)
		)
		(property "Description" "SMT test point"
			(at 0 0 0)
			(layer "F.Fab")
			(hide yes)
			(effects
				(font
					(size 1.27 1.27)
					(thickness 0.15)
				)
			)
		)
		(property "MPN" ""
			(at 0 0 180)
			(unlocked yes)
			(layer "F.Fab")
			(hide yes)
			(effects
				(font
					(size 1 1)
					(thickness 0.15)
				)
			)
		)
		(property "Manufacturer" ""
			(at 0 0 180)
			(unlocked yes)
			(layer "F.Fab")
			(hide yes)
			(effects
				(font
					(size 1 1)
					(thickness 0.15)
				)
			)
		)
		(property "Author" "Antmicro"
			(at 0 0 180)
			(unlocked yes)
			(layer "F.Fab")
			(hide yes)
			(effects
				(font
					(size 1 1)
					(thickness 0.15)
				)
			)
		)
		(property "License" "Apache-2.0"
			(at 0 0 180)
			(unlocked yes)
			(layer "F.Fab")
			(hide yes)
			(effects
				(font
					(size 1 1)
					(thickness 0.15)
				)
			)
		)
		(property "Public" "False"
			(at 0 0 180)
			(unlocked yes)
			(layer "F.Fab")
			(hide yes)
			(effects
				(font
					(size 1 1)
					(thickness 0.15)
				)
			)
		)
		(sheetname "Root")
		(sheetfile "jetson-orin-baseboard-oculink-expansion.kicad_sch")
		(attr exclude_from_pos_files exclude_from_bom)
		(fp_circle
			(center 0 0)
			(end 0.475 0)
			(stroke
				(width 0.05)
				(type default)
			)
			(fill none)
			(layer "F.CrtYd")
		)
		(fp_text user "License: Apache-2.0"
			(at -0.4 5.101 0)
			(layer "F.Fab")
			(hide yes)
			(effects
				(font
					(size 0.7 0.7)
					(thickness 0.15)
				)
				(justify right top)
			)
		)
		(fp_text user "Author: Antmicro"
			(at -0.4 3.901 0)
			(layer "F.Fab")
			(hide yes)
			(effects
				(font
					(size 0.7 0.7)
					(thickness 0.15)
				)
				(justify right top)
			)
		)
		(fp_text user "${REFERENCE}"
			(at -0.4 2.7 0)
			(layer "F.Fab")
			(hide yes)
			(effects
				(font
					(size 0.7 0.7)
					(thickness 0.15)
				)
				(justify right top)
			)
		)
		(pad "1" smd circle
			(at 0 0 180)
			(size 0.75 0.75)
			(layers "F.Cu" "F.Mask")
			(net 109 "Net-(U2-I2C_{DONE})")
			(pinfunction "1")
			(pintype "passive")
		)
	)
	(footprint "antmicro-footprints:C_0402_1005Metric"
		(layer "F.Cu")
		(at 129.2 109.278 180)
		(descr "Capacitor SMD 0402")
		(tags "capacitor SMD 0402")
		(property "Reference" "C38"
			(at 0.9 0.37 0)
			(layer "F.SilkS")
			(effects
				(font
					(size 0.7 0.7)
					(thickness 0.15)
				)
				(justify right top)
			)
		)
		(property "Value" "C_220n_0402"
			(at -1.022927 2.155213 0)
			(layer "F.Fab")
			(effects
				(font
					(size 0.7 0.7)
					(thickness 0.15)
				)
				(justify right top)
			)
		)
		(property "Footprint" "antmicro-footprints:C_0402_1005Metric"
			(at 0 0 0)
			(layer "F.Fab")
			(hide yes)
			(effects
				(font
					(size 1.27 1.27)
					(thickness 0.15)
				)
			)
		)
		(property "Datasheet" "https://www.yageo.com/en/Chart/Download/pdf/CC0402KRX5R6BB224"
			(at 0 0 0)
			(layer "F.Fab")
			(hide yes)
			(effects
				(font
					(size 1.27 1.27)
					(thickness 0.15)
				)
			)
		)
		(property "Description" "SMD Multilayer Ceramic Capacitor, 0.22 µF, 10 V, 0402 [1005 Metric], ± 10%, X5R, CC Series"
			(at 0 0 0)
			(layer "F.Fab")
			(hide yes)
			(effects
				(font
					(size 1.27 1.27)
					(thickness 0.15)
				)
			)
		)
		(property "MPN" "CC0402KRX5R6BB224"
			(at 0 0 180)
			(unlocked yes)
			(layer "F.Fab")
			(hide yes)
			(effects
				(font
					(size 1 1)
					(thickness 0.15)
				)
			)
		)
		(property "Manufacturer" "YAGEO"
			(at 0 0 180)
			(unlocked yes)
			(layer "F.Fab")
			(hide yes)
			(effects
				(font
					(size 1 1)
					(thickness 0.15)
				)
			)
		)
		(property "License" "Apache-2.0"
			(at 0 0 180)
			(unlocked yes)
			(layer "F.Fab")
			(hide yes)
			(effects
				(font
					(size 1 1)
					(thickness 0.15)
				)
			)
		)
		(property "Author" "Antmicro"
			(at 0 0 180)
			(unlocked yes)
			(layer "F.Fab")
			(hide yes)
			(effects
				(font
					(size 1 1)
					(thickness 0.15)
				)
			)
		)
		(property "Val" "220n"
			(at 0 0 180)
			(unlocked yes)
			(layer "F.Fab")
			(hide yes)
			(effects
				(font
					(size 1 1)
					(thickness 0.15)
				)
			)
		)
		(property "Voltage" ""
			(at 0 0 180)
			(unlocked yes)
			(layer "F.Fab")
			(hide yes)
			(effects
				(font
					(size 1 1)
					(thickness 0.15)
				)
			)
		)
		(property "Dielectric" ""
			(at 0 0 180)
			(unlocked yes)
			(layer "F.Fab")
			(hide yes)
			(effects
				(font
					(size 1 1)
					(thickness 0.15)
				)
			)
		)
		(property "Public" "False"
			(at 0 0 180)
			(unlocked yes)
			(layer "F.Fab")
			(hide yes)
			(effects
				(font
					(size 1 1)
					(thickness 0.15)
				)
			)
		)
		(sheetname "Root")
		(sheetfile "jetson-orin-baseboard-oculink-expansion.kicad_sch")
		(attr smd)
		(fp_rect
			(start -0.925 -0.47)
			(end 0.925 0.47)
			(stroke
				(width 0.05)
				(type default)
			)
			(fill none)
			(layer "F.CrtYd")
		)
		(fp_line
			(start 0.504 0.248)
			(end -0.494 0.248)
			(stroke
				(width 0.15)
				(type solid)
			)
			(layer "F.Fab")
		)
		(fp_line
			(start 0.504 -0.25)
			(end 0.504 0.248)
			(stroke
				(width 0.15)
				(type solid)
			)
			(layer "F.Fab")
		)
		(fp_line
			(start -0.494 0.248)
			(end -0.494 -0.25)
			(stroke
				(width 0.15)
				(type solid)
			)
			(layer "F.Fab")
		)
		(fp_line
			(start -0.494 -0.25)
			(end 0.504 -0.25)
			(stroke
				(width 0.15)
				(type solid)
			)
			(layer "F.Fab")
		)
		(fp_text user "License: Apache-2.0"
			(at -0.939 5.799 0)
			(layer "F.Fab")
			(hide yes)
			(effects
				(font
					(size 0.7 0.7)
					(thickness 0.15)
				)
				(justify right top)
			)
		)
		(fp_text user "Author: Antmicro"
			(at -0.939 3.399 0)
			(layer "F.Fab")
			(hide yes)
			(effects
				(font
					(size 0.7 0.7)
					(thickness 0.15)
				)
				(justify right top)
			)
		)
		(fp_text user "${REFERENCE}"
			(at -0.939 4.599 0)
			(layer "F.Fab")
			(hide yes)
			(effects
				(font
					(size 0.7 0.7)
					(thickness 0.15)
				)
				(justify right top)
			)
		)
		(pad "1" smd roundrect
			(at -0.48 0 180)
			(size 0.59 0.64)
			(layers "F.Cu" "F.Paste" "F.Mask")
			(roundrect_rratio 0.25)
			(net 78 "/PCIE_{I}_RX0+")
			(pintype "passive")
		)
		(pad "2" smd roundrect
			(at 0.48 0 180)
			(size 0.59 0.64)
			(layers "F.Cu" "F.Paste" "F.Mask")
			(roundrect_rratio 0.25)
			(net 77 "/PCIE_{I}_C.RX0+")
			(pintype "passive")
		)
	)
	(footprint "antmicro-footprints:SOT-23-8"
		(layer "F.Cu")
		(at 144.099 142.299 180)
		(descr "http://www.ti.com/lit/ds/symlink/ina219.pdf")
		(property "Reference" "U1"
			(at -0.301 -1.901 90)
			(layer "F.SilkS")
			(effects
				(font
					(size 0.7 0.7)
					(thickness 0.15)
				)
				(justify right top)
			)
		)
		(property "Value" "MAX3373EEKA+"
			(at -4.101 -2.301 0)
			(layer "F.Fab")
			(effects
				(font
					(size 0.7 0.7)
					(thickness 0.15)
				)
				(justify right top)
			)
		)
		(property "Footprint" "antmicro-footprints:SOT-23-8"
			(at 0 0 0)
			(layer "F.Fab")
			(hide yes)
			(effects
				(font
					(size 1.27 1.27)
					(thickness 0.15)
				)
			)
		)
		(property "Datasheet" "https://www.analog.com/en/products/max3373e.html"
			(at 0 0 0)
			(layer "F.Fab")
			(hide yes)
			(effects
				(font
					(size 1.27 1.27)
					(thickness 0.15)
				)
			)
		)
		(property "Description" "±15kV ESD-Protected, 1µA, 16Mbps, Dual/Quad Low-Voltage Level Translators in UCSP"
			(at 0 0 0)
			(layer "F.Fab")
			(hide yes)
			(effects
				(font
					(size 1.27 1.27)
					(thickness 0.15)
				)
			)
		)
		(property "MPN" "MAX3373EEKA+"
			(at 0 0 180)
			(unlocked yes)
			(layer "F.Fab")
			(hide yes)
			(effects
				(font
					(size 1 1)
					(thickness 0.15)
				)
			)
		)
		(property "Manufacturer" "Analog Devices"
			(at 0 0 180)
			(unlocked yes)
			(layer "F.Fab")
			(hide yes)
			(effects
				(font
					(size 1 1)
					(thickness 0.15)
				)
			)
		)
		(property "Author" "Antmicro"
			(at 0 0 180)
			(unlocked yes)
			(layer "F.Fab")
			(hide yes)
			(effects
				(font
					(size 1 1)
					(thickness 0.15)
				)
			)
		)
		(property "License" "Apache-2.0"
			(at 0 0 180)
			(unlocked yes)
			(layer "F.Fab")
			(hide yes)
			(effects
				(font
					(size 1 1)
					(thickness 0.15)
				)
			)
		)
		(sheetname "Root")
		(sheetfile "jetson-orin-baseboard-oculink-expansion.kicad_sch")
		(attr smd)
		(fp_line
			(start 1 1.6)
			(end 0.6 1.6)
			(stroke
				(width 0.15)
				(type solid)
			)
			(layer "F.SilkS")
		)
		(fp_line
			(start 1 1.3)
			(end 1 1.6)
			(stroke
				(width 0.15)
				(type solid)
			)
			(layer "F.SilkS")
		)
		(fp_line
			(start 1 -1.3)
			(end 1 -1.6)
			(stroke
				(width 0.15)
				(type solid)
			)
			(layer "F.SilkS")
		)
		(fp_line
			(start 1 -1.6)
			(end 0.625 -1.6)
			(stroke
				(width 0.15)
				(type solid)
			)
			(layer "F.SilkS")
		)
		(fp_line
			(start -0.613 1.6)
			(end -0.987 1.6)
			(stroke
				(width 0.15)
				(type solid)
			)
			(layer "F.SilkS")
		)
		(fp_line
			(start -0.987 1.6)
			(end -0.987 1.324)
			(stroke
				(width 0.15)
				(type solid)
			)
			(layer "F.SilkS")
		)
		(fp_line
			(start -1 -1.3)
			(end -1 -1.6)
			(stroke
				(width 0.15)
				(type solid)
			)
			(layer "F.SilkS")
		)
		(fp_line
			(start -1 -1.6)
			(end -0.6 -1.6)
			(stroke
				(width 0.15)
				(type solid)
			)
			(layer "F.SilkS")
		)
		(fp_circle
			(center -1.3 -1.4)
			(end -1.25 -1.4)
			(stroke
				(width 0.15)
				(type solid)
			)
			(fill solid)
			(layer "F.SilkS")
		)
		(fp_rect
			(start -1.9 -1.75)
			(end 1.898 1.75)
			(stroke
				(width 0.05)
				(type solid)
			)
			(fill none)
			(layer "F.CrtYd")
		)
		(fp_line
			(start -1.4 -1.25)
			(end -1.2 -1.45)
			(stroke
				(width 0.15)
				(type solid)
			)
			(layer "F.Fab")
		)
		(fp_rect
			(start -1.401 -1.45)
			(end 1.398 1.449)
			(stroke
				(width 0.15)
				(type solid)
			)
			(fill none)
			(layer "F.Fab")
		)
		(fp_text user "Author: Antmicro"
			(at -2.925 7.2 0)
			(layer "F.Fab")
			(hide yes)
			(effects
				(font
					(size 0.7 0.7)
					(thickness 0.15)
				)
				(justify right top)
			)
		)
		(fp_text user "${REFERENCE}"
			(at -2.925 4.8 0)
			(layer "F.Fab")
			(hide yes)
			(effects
				(font
					(size 0.7 0.7)
					(thickness 0.15)
				)
				(justify right top)
			)
		)
		(fp_text user "License: Apache-2.0"
			(at -2.925 6 0)
			(layer "F.Fab")
			(hide yes)
			(effects
				(font
					(size 0.7 0.7)
					(thickness 0.15)
				)
				(justify right top)
			)
		)
		(pad "1" smd roundrect
			(at -1.3 -0.975 90)
			(size 0.45 1.1)
			(layers "F.Cu" "F.Paste" "F.Mask")
			(roundrect_rratio 0.25)
			(net 71 "/~{CPRSNT}")
			(pinfunction "IO_V_{CC}2")
			(pintype "bidirectional")
		)
		(pad "2" smd roundrect
			(at -1.3 -0.325 90)
			(size 0.45 1.1)
			(layers "F.Cu" "F.Paste" "F.Mask")
			(roundrect_rratio 0.25)
			(net 51 "GND")
			(pinfunction "GND")
			(pintype "power_in")
		)
		(pad "3" smd roundrect
			(at -1.3 0.325 90)
			(size 0.45 1.1)
			(layers "F.Cu" "F.Paste" "F.Mask")
			(roundrect_rratio 0.25)
			(net 20 "+1V8")
			(pinfunction "V_{L}")
			(pintype "power_in")
		)
		(pad "4" smd roundrect
			(at -1.3 0.975 90)
			(size 0.45 1.1)
			(layers "F.Cu" "F.Paste" "F.Mask")
			(roundrect_rratio 0.25)
			(net 67 "/JOB_GPIO07")
			(pinfunction "IO_V_{L}2")
			(pintype "bidirectional")
		)
		(pad "5" smd roundrect
			(at 1.3 0.975 90)
			(size 0.45 1.1)
			(layers "F.Cu" "F.Paste" "F.Mask")
			(roundrect_rratio 0.25)
			(net 65 "/JOB_GPIO09")
			(pinfunction "IO_V_{L}1")
			(pintype "bidirectional")
		)
		(pad "6" smd roundrect
			(at 1.3 0.325 90)
			(size 0.45 1.1)
			(layers "F.Cu" "F.Paste" "F.Mask")
			(roundrect_rratio 0.25)
			(net 70 "Net-(U1-~{THREE_STATE})")
			(pinfunction "~{THREE_STATE}")
			(pintype "input")
		)
		(pad "7" smd roundrect
			(at 1.3 -0.325 90)
			(size 0.45 1.1)
			(layers "F.Cu" "F.Paste" "F.Mask")
			(roundrect_rratio 0.25)
			(net 23 "+3V3")
			(pinfunction "V_{CC}")
			(pintype "power_in")
		)
		(pad "8" smd roundrect
			(at 1.3 -0.975 90)
			(size 0.45 1.1)
			(layers "F.Cu" "F.Paste" "F.Mask")
			(roundrect_rratio 0.25)
			(net 69 "/~{PCIE_CWAKE}")
			(pinfunction "IO_V_{CC}1")
			(pintype "bidirectional")
		)
	)
)
